(kicad_pcb
	(version 20260206)
	(generator "pcbnew")
	(generator_version "10.0")
	(general
		(thickness 1.6)
		(legacy_teardrops no)
	)
	(paper "A4")
	(title_block
		(title "v1-chassis-manager — T6M_CM_d_v01_1031_1645.brd")
		(comment 1 "Open CloudServer (Microsoft) / footprints 238-245 of 2512")
	)
	(layers
		(0 "F.Cu" signal "TOP")
		(4 "In1.Cu" signal "GND1")
		(6 "In2.Cu" signal "IN1")
		(8 "In3.Cu" signal "VCC1")
		(10 "In4.Cu" signal "VCC2")
		(12 "In5.Cu" signal "GND2")
		(14 "In6.Cu" signal "IN2")
		(16 "In7.Cu" signal "IN3")
		(18 "In8.Cu" signal "GND3")
		(2 "B.Cu" signal "BOTTOM")
		(9 "F.Adhes" user "F.Adhesive")
		(11 "B.Adhes" user "B.Adhesive")
		(13 "F.Paste" user "Package Geometry/Pastemask Top")
		(15 "B.Paste" user "Package Geometry/Pastemask Bottom")
		(5 "F.SilkS" user "Ref Des/Silkscreen Top")
		(7 "B.SilkS" user "Ref Des/Silkscreen Bottom")
		(1 "F.Mask" user "Board Geometry/Soldermask Top")
		(3 "B.Mask" user "Board Geometry/Soldermask Bottom")
		(17 "Dwgs.User" user "User.Drawings")
		(19 "Cmts.User" user "User.Comments")
		(21 "Eco1.User" user "User.Eco1")
		(23 "Eco2.User" user "User.Eco2")
		(25 "Edge.Cuts" user "Board Geometry/Outline")
		(27 "Margin" user)
		(31 "F.CrtYd" user "Package Geometry/Place Bound Top")
		(29 "B.CrtYd" user "Package Geometry/Place Bound Bottom")
		(35 "F.Fab" user "Ref Des/Assembly Top")
		(33 "B.Fab" user "Ref Des/Assembly Bottom")
	)
	(footprint ""
		(layer "F.Cu")
		(at 126.563628 -158.606744 180)
		(property "Reference" "U116"
			(at 60.31611 -109.30128 90)
			(unlocked yes)
			(layer "F.SilkS")
			(effects
				(font
					(size 0.7874 0.5842)
					(thickness 0.1524)
				)
			)
		)
		(property "Value" ""
			(at 0 0 180)
			(layer "F.Fab")
			(effects
				(font
					(size 1.27 1.27)
				)
			)
		)
		(duplicate_pad_numbers_are_jumpers no)
		(fp_line
			(start 1.651 1.905)
			(end -1.651 1.905)
			(stroke
				(width 0.1524)
				(type default)
			)
			(layer "F.SilkS")
		)
		(fp_line
			(start 1.651 -1.905)
			(end 1.651 1.905)
			(stroke
				(width 0.1524)
				(type default)
			)
			(layer "F.SilkS")
		)
		(fp_line
			(start -1.651 1.905)
			(end -1.651 -1.905)
			(stroke
				(width 0.1524)
				(type default)
			)
			(layer "F.SilkS")
		)
		(fp_line
			(start -1.651 -1.905)
			(end 1.651 -1.905)
			(stroke
				(width 0.1524)
				(type default)
			)
			(layer "F.SilkS")
		)
		(fp_poly
			(pts
				(xy -1.524 0.7112) (xy -1.524 1.7526) (xy -0.508 1.7526) (xy -0.508 0.6985) (xy 0.508 0.6985) (xy 0.508 1.7526)
				(xy 1.524 1.7526) (xy 1.524 0.6985) (xy 1.524 -0.6985) (xy 0.508 -0.6985) (xy 0.508 -1.7526) (xy -0.508 -1.7526)
				(xy -0.508 -0.6985) (xy -1.524 -0.6985) (xy -1.524 0.6985)
			)
			(stroke
				(width 0)
				(type default)
			)
			(fill no)
			(layer "F.CrtYd")
		)
		(fp_text user "S"
			(at 0.401828 2.537206 0)
			(unlocked yes)
			(layer "F.SilkS")
			(effects
				(font
					(size 0.635 0.4064)
					(thickness 0.1524)
				)
			)
		)
		(fp_text user "D"
			(at 0.375412 -2.77114 0)
			(unlocked yes)
			(layer "F.SilkS")
			(effects
				(font
					(size 0.635 0.4064)
					(thickness 0.1524)
				)
			)
		)
		(fp_text user "G"
			(at -0.715772 2.537206 0)
			(unlocked yes)
			(layer "F.SilkS")
			(effects
				(font
					(size 0.635 0.4064)
					(thickness 0.1524)
				)
			)
		)
		(pad "D" smd rect
			(at 0 -1.1176 180)
			(size 1.016 1.27)
			(layers "F.Cu" "F.Mask" "F.Paste")
			(net "I2C_PSU1_SCL")
		)
		(pad "G" smd rect
			(at -1.016 1.1176 180)
			(size 1.016 1.27)
			(layers "F.Cu" "F.Mask" "F.Paste")
			(net "PMBUS1_EN")
		)
		(pad "S" smd rect
			(at 1.016 1.1176 180)
			(size 1.016 1.27)
			(layers "F.Cu" "F.Mask" "F.Paste")
			(net "I2C_PSU1_SCL_MOS")
		)
	)
	(footprint ""
		(layer "F.Cu")
		(at 38.126416 -185.583068)
		(property "Reference" "D20"
			(at 0.114554 -4.710176 90)
			(unlocked yes)
			(layer "F.SilkS")
			(effects
				(font
					(size 0.7874 0.5842)
					(thickness 0.1524)
				)
			)
		)
		(property "Value" ""
			(at 0 0 0)
			(layer "F.Fab")
			(effects
				(font
					(size 1.27 1.27)
				)
			)
		)
		(duplicate_pad_numbers_are_jumpers no)
		(fp_line
			(start -1.519936 -1.6002)
			(end 1.519936 -1.6002)
			(stroke
				(width 0.1524)
				(type default)
			)
			(layer "F.SilkS")
		)
		(fp_line
			(start -1.519936 1.6002)
			(end -1.519936 -1.5748)
			(stroke
				(width 0.1524)
				(type default)
			)
			(layer "F.SilkS")
		)
		(fp_line
			(start 1.519936 -1.6002)
			(end 1.519936 1.6002)
			(stroke
				(width 0.1524)
				(type default)
			)
			(layer "F.SilkS")
		)
		(fp_line
			(start 1.519936 1.6002)
			(end -1.519936 1.6002)
			(stroke
				(width 0.1524)
				(type default)
			)
			(layer "F.SilkS")
		)
		(fp_poly
			(pts
				(xy -1.519936 0.700024) (xy -1.3716 0.700024) (xy -1.3716 1.4732) (xy -0.5334 1.4732) (xy -0.5334 0.700024)
				(xy 0.5334 0.700024) (xy 0.5334 1.4732) (xy 1.3716 1.4732) (xy 1.3716 0.700024) (xy 1.519936 0.700024)
				(xy 1.519936 -0.700024) (xy 0.4064 -0.700024) (xy 0.4064 -1.4732) (xy -0.4064 -1.4732) (xy -0.4064 -0.700024)
				(xy -1.519936 -0.700024)
			)
			(stroke
				(width 0)
				(type default)
			)
			(fill no)
			(layer "F.CrtYd")
		)
		(fp_line
			(start -1.519936 -0.700024)
			(end 1.519936 -0.700024)
			(stroke
				(width 0.1)
				(type default)
			)
			(layer "F.Fab")
		)
		(fp_line
			(start -1.519936 0.700024)
			(end -1.519936 -0.700024)
			(stroke
				(width 0.1)
				(type default)
			)
			(layer "F.Fab")
		)
		(fp_line
			(start 1.519936 -0.700024)
			(end 1.519936 0.700024)
			(stroke
				(width 0.1)
				(type default)
			)
			(layer "F.Fab")
		)
		(fp_line
			(start 1.519936 0.700024)
			(end -1.519936 0.700024)
			(stroke
				(width 0.1)
				(type default)
			)
			(layer "F.Fab")
		)
		(fp_text user "1"
			(at -1.761236 0.8001 0)
			(unlocked yes)
			(layer "F.SilkS")
			(effects
				(font
					(size 0.635 0.4064)
					(thickness 0.1524)
				)
			)
		)
		(fp_text user "3"
			(at 0 -2.08915 0)
			(unlocked yes)
			(layer "F.SilkS")
			(effects
				(font
					(size 0.635 0.4064)
					(thickness 0.1524)
				)
			)
		)
		(fp_text user "2"
			(at 0.78105 2.431796 0)
			(unlocked yes)
			(layer "F.SilkS")
			(effects
				(font
					(size 0.635 0.4064)
					(thickness 0.1524)
				)
			)
		)
		(pad "1" smd rect
			(at -0.94996 0.999998)
			(size 0.8128 0.9144)
			(layers "F.Cu" "F.Mask" "F.Paste")
			(net "GND")
		)
		(pad "2" smd rect
			(at 0.94996 0.999998)
			(size 0.8128 0.9144)
			(layers "F.Cu" "F.Mask" "F.Paste")
			(net "Net_1678")
		)
		(pad "3" smd rect
			(at 0 -0.999998)
			(size 0.8128 0.9144)
			(layers "F.Cu" "F.Mask" "F.Paste")
			(net "P12V_PDB")
		)
	)
	(footprint ""
		(layer "F.Cu")
		(at 41.862248 -169.659046 90)
		(property "Reference" "R1070"
			(at -2.440686 -2.464562 90)
			(unlocked yes)
			(layer "F.SilkS")
			(effects
				(font
					(size 0.7874 0.5842)
					(thickness 0.1524)
				)
				(justify left)
			)
		)
		(property "Value" ""
			(at 0 0 90)
			(layer "F.Fab")
			(effects
				(font
					(size 1.27 1.27)
				)
			)
		)
		(duplicate_pad_numbers_are_jumpers no)
		(fp_line
			(start 0.7874 -0.4064)
			(end 0.7874 0.4064)
			(stroke
				(width 0.1524)
				(type default)
			)
			(layer "F.SilkS")
		)
		(fp_line
			(start -0.7874 -0.4064)
			(end 0.7874 -0.4064)
			(stroke
				(width 0.1524)
				(type default)
			)
			(layer "F.SilkS")
		)
		(fp_line
			(start 0.7874 0.4064)
			(end -0.7874 0.4064)
			(stroke
				(width 0.1524)
				(type default)
			)
			(layer "F.SilkS")
		)
		(fp_line
			(start -0.7874 0.4064)
			(end -0.7874 -0.4064)
			(stroke
				(width 0.1524)
				(type default)
			)
			(layer "F.SilkS")
		)
		(fp_poly
			(pts
				(xy -0.508 0.2794) (xy -0.508 0.2286) (xy -0.635 0.2286) (xy -0.635 -0.254) (xy -0.5334 -0.254)
				(xy -0.5334 -0.2794) (xy 0.5334 -0.2794) (xy 0.5334 -0.254) (xy 0.635 -0.254) (xy 0.635 0.254) (xy 0.5334 0.254)
				(xy 0.5334 0.2794)
			)
			(stroke
				(width 0)
				(type default)
			)
			(fill no)
			(layer "F.CrtYd")
		)
		(pad "1" smd rect
			(at 0.40005 0 90)
			(size 0.4572 0.508)
			(layers "F.Cu" "F.Mask" "F.Paste")
			(net "N53103066")
		)
		(pad "2" smd rect
			(at -0.40005 0 90)
			(size 0.4572 0.508)
			(layers "F.Cu" "F.Mask" "F.Paste")
			(net "P12V_DBG")
		)
	)
	(footprint ""
		(layer "F.Cu")
		(at 93.993462 -15.849092 90)
		(property "Reference" "R192"
			(at -0.249428 -1.191768 90)
			(unlocked yes)
			(layer "F.SilkS")
			(effects
				(font
					(size 0.7874 0.5842)
					(thickness 0.1524)
				)
				(justify left)
			)
		)
		(property "Value" ""
			(at 0 0 90)
			(layer "F.Fab")
			(effects
				(font
					(size 1.27 1.27)
				)
			)
		)
		(duplicate_pad_numbers_are_jumpers no)
		(fp_line
			(start 0.7874 -0.4064)
			(end 0.7874 0.4064)
			(stroke
				(width 0.1524)
				(type default)
			)
			(layer "F.SilkS")
		)
		(fp_line
			(start -0.7874 -0.4064)
			(end 0.7874 -0.4064)
			(stroke
				(width 0.1524)
				(type default)
			)
			(layer "F.SilkS")
		)
		(fp_line
			(start 0.7874 0.4064)
			(end -0.7874 0.4064)
			(stroke
				(width 0.1524)
				(type default)
			)
			(layer "F.SilkS")
		)
		(fp_line
			(start -0.7874 0.4064)
			(end -0.7874 -0.4064)
			(stroke
				(width 0.1524)
				(type default)
			)
			(layer "F.SilkS")
		)
		(fp_poly
			(pts
				(xy -0.508 0.2794) (xy -0.508 0.2286) (xy -0.635 0.2286) (xy -0.635 -0.254) (xy -0.5334 -0.254)
				(xy -0.5334 -0.2794) (xy 0.5334 -0.2794) (xy 0.5334 -0.254) (xy 0.635 -0.254) (xy 0.635 0.254) (xy 0.5334 0.254)
				(xy 0.5334 0.2794)
			)
			(stroke
				(width 0)
				(type default)
			)
			(fill no)
			(layer "F.CrtYd")
		)
		(pad "1" smd rect
			(at 0.40005 0 90)
			(size 0.4572 0.508)
			(layers "F.Cu" "F.Mask" "F.Paste")
			(net "LPC_CPU_NODE1_LAD2")
		)
		(pad "2" smd rect
			(at -0.40005 0 90)
			(size 0.4572 0.508)
			(layers "F.Cu" "F.Mask" "F.Paste")
			(net "LPC_CPU_TPM_LAD2")
		)
	)
	(footprint ""
		(layer "F.Cu")
		(at 145.65376 -185.205624 90)
		(property "Reference" "C756"
			(at 4.768088 -0.544068 90)
			(unlocked yes)
			(layer "F.SilkS")
			(effects
				(font
					(size 0.7874 0.5842)
					(thickness 0.1524)
				)
				(justify left)
			)
		)
		(property "Value" ""
			(at 0 0 90)
			(layer "F.Fab")
			(effects
				(font
					(size 1.27 1.27)
				)
			)
		)
		(duplicate_pad_numbers_are_jumpers no)
		(fp_line
			(start 0.7874 -0.4064)
			(end 0.7874 0.4064)
			(stroke
				(width 0.1524)
				(type default)
			)
			(layer "F.SilkS")
		)
		(fp_line
			(start -0.7874 -0.4064)
			(end 0.7874 -0.4064)
			(stroke
				(width 0.1524)
				(type default)
			)
			(layer "F.SilkS")
		)
		(fp_line
			(start 0 0.381)
			(end 0 -0.381)
			(stroke
				(width 0.1524)
				(type default)
			)
			(layer "F.SilkS")
		)
		(fp_line
			(start 0.7874 0.4064)
			(end -0.7874 0.4064)
			(stroke
				(width 0.1524)
				(type default)
			)
			(layer "F.SilkS")
		)
		(fp_line
			(start -0.7874 0.4064)
			(end -0.7874 -0.4064)
			(stroke
				(width 0.1524)
				(type default)
			)
			(layer "F.SilkS")
		)
		(fp_poly
			(pts
				(xy -0.5334 0.254) (xy -0.635 0.254) (xy -0.635 0.2286) (xy -0.635 -0.254) (xy -0.5334 -0.254) (xy -0.5334 -0.2794)
				(xy 0.5334 -0.2794) (xy 0.5334 -0.254) (xy 0.635 -0.254) (xy 0.635 0.254) (xy 0.5334 0.254) (xy 0.5334 0.2794)
				(xy -0.508 0.2794) (xy -0.5334 0.2794)
			)
			(stroke
				(width 0)
				(type default)
			)
			(fill no)
			(layer "F.CrtYd")
		)
		(pad "1" smd rect
			(at 0.40005 0 90)
			(size 0.4572 0.508)
			(layers "F.Cu" "F.Mask" "F.Paste")
			(net "UART_T12_NODE3_RXD")
		)
		(pad "2" smd rect
			(at -0.40005 0 90)
			(size 0.4572 0.508)
			(layers "F.Cu" "F.Mask" "F.Paste")
			(net "GND")
		)
	)
	(footprint ""
		(layer "F.Cu")
		(at 182.819294 -134.39902 -90)
		(property "Reference" "Q27"
			(at 2.188464 -12.60221 90)
			(unlocked yes)
			(layer "F.SilkS")
			(effects
				(font
					(size 0.7874 0.5842)
					(thickness 0.1524)
				)
				(justify left)
			)
		)
		(property "Value" ""
			(at 0 0 270)
			(layer "F.Fab")
			(effects
				(font
					(size 1.27 1.27)
				)
			)
		)
		(duplicate_pad_numbers_are_jumpers no)
		(fp_line
			(start -0.5842 2.48412)
			(end -0.5842 -0.5842)
			(stroke
				(width 0.1524)
				(type default)
			)
			(layer "F.SilkS")
		)
		(fp_line
			(start 2.584196 2.48412)
			(end -0.5842 2.48412)
			(stroke
				(width 0.1524)
				(type default)
			)
			(layer "F.SilkS")
		)
		(fp_line
			(start -0.5842 -0.5842)
			(end 2.584196 -0.5842)
			(stroke
				(width 0.1524)
				(type default)
			)
			(layer "F.SilkS")
		)
		(fp_line
			(start 2.584196 -0.5842)
			(end 2.584196 2.48412)
			(stroke
				(width 0.1524)
				(type default)
			)
			(layer "F.SilkS")
		)
		(fp_poly
			(pts
				(xy -0.508 -0.4572) (xy 0.299974 -0.4572) (xy 0.299974 -0.54991) (xy 1.700022 -0.54991) (xy 1.700022 0.49276)
				(xy 2.507996 0.49276) (xy 2.507996 1.40716) (xy 1.700022 1.40716) (xy 1.700022 2.450084) (xy 0.299974 2.450084)
				(xy 0.299974 2.35712) (xy -0.508 2.35712)
			)
			(stroke
				(width 0)
				(type default)
			)
			(fill no)
			(layer "F.CrtYd")
		)
		(fp_line
			(start 0.299974 2.450084)
			(end 0.299974 -0.54991)
			(stroke
				(width 0.1)
				(type default)
			)
			(layer "F.Fab")
		)
		(fp_line
			(start 1.700022 2.450084)
			(end 0.299974 2.450084)
			(stroke
				(width 0.1)
				(type default)
			)
			(layer "F.Fab")
		)
		(fp_line
			(start 0.299974 -0.54991)
			(end 1.700022 -0.54991)
			(stroke
				(width 0.1)
				(type default)
			)
			(layer "F.Fab")
		)
		(fp_line
			(start 1.700022 -0.54991)
			(end 1.700022 2.450084)
			(stroke
				(width 0.1)
				(type default)
			)
			(layer "F.Fab")
		)
		(fp_text user "E"
			(at -1.506474 1.979676 0)
			(unlocked yes)
			(layer "F.SilkS")
			(effects
				(font
					(size 0.635 0.4064)
					(thickness 0.1524)
				)
				(justify left)
			)
		)
		(fp_text user "C"
			(at 3.154172 1.685036 90)
			(unlocked yes)
			(layer "F.SilkS")
			(effects
				(font
					(size 0.635 0.4064)
					(thickness 0.1524)
				)
				(justify left)
			)
		)
		(fp_text user "B"
			(at 0.704596 -0.817626 0)
			(unlocked yes)
			(layer "F.SilkS")
			(effects
				(font
					(size 0.635 0.4064)
					(thickness 0.1524)
				)
				(justify left)
			)
		)
		(fp_text user "E"
			(at -1.5748 1.95707 270)
			(unlocked yes)
			(layer "F.Fab")
			(effects
				(font
					(size 0.7874 0.5842)
					(thickness 0.000001)
				)
				(justify left)
			)
		)
		(fp_text user "C"
			(at 2.8702 0.99187 270)
			(unlocked yes)
			(layer "F.Fab")
			(effects
				(font
					(size 0.7874 0.5842)
					(thickness 0.000001)
				)
				(justify left)
			)
		)
		(fp_text user "B"
			(at -1.5494 0.00127 270)
			(unlocked yes)
			(layer "F.Fab")
			(effects
				(font
					(size 0.7874 0.5842)
					(thickness 0.000001)
				)
				(justify left)
			)
		)
		(pad "B" smd rect
			(at 0 0)
			(size 0.8128 0.9144)
			(layers "F.Cu" "F.Mask" "F.Paste")
			(net "FM_NODE1_DFX_GPIO_GRP05_R")
		)
		(pad "C" smd rect
			(at 1.999996 0.94996)
			(size 0.8128 0.9144)
			(layers "F.Cu" "F.Mask" "F.Paste")
			(net "FM_NODE1_CORE0_1_RST_L")
		)
		(pad "E" smd rect
			(at 0 1.89992)
			(size 0.8128 0.9144)
			(layers "F.Cu" "F.Mask" "F.Paste")
			(net "GND")
		)
	)
	(footprint ""
		(layer "F.Cu")
		(at 96.697546 -138.030458 180)
		(property "Reference" "J21"
			(at 0.057404 1.38049 90)
			(unlocked yes)
			(layer "F.SilkS")
			(effects
				(font
					(size 0.7874 0.5842)
					(thickness 0.1524)
				)
				(justify left)
			)
		)
		(property "Value" ""
			(at 0 0 180)
			(layer "F.Fab")
			(effects
				(font
					(size 1.27 1.27)
				)
			)
		)
		(duplicate_pad_numbers_are_jumpers no)
		(fp_poly
			(pts
				(xy 0.2794 0.907796) (xy 0.254 0.907796) (xy 0.254 1.0414) (xy -0.254 1.0414) (xy -0.254 1.034796)
				(xy -0.254 0.933196) (xy -0.2794 0.933196) (xy -0.2794 -0.133604) (xy -0.254 -0.133604) (xy -0.254 -0.235204)
				(xy 0.254 -0.235204) (xy 0.254 -0.133604) (xy 0.2794 -0.133604)
			)
			(stroke
				(width 0)
				(type default)
			)
			(fill no)
			(layer "F.CrtYd")
		)
		(pad "1" smd custom
			(at 0 -0.000254 180)
			(size 0.127 0.127)
			(layers "F.Cu" "F.Mask" "F.Paste")
			(net "P1V05_SUS_NODE1")
			(options
				(clearance outline)
				(anchor circle)
			)
			(primitives
				(gr_poly
					(pts
						(xy -0.127 0.508) (xy -0.127 -0.0508) (xy -0.254 -0.0508) (xy -0.254 -0.508) (xy 0.254 -0.508)
						(xy 0.254 -0.0508) (xy 0.127 -0.0508) (xy 0.127 0.508)
					)
					(width 0)
					(fill yes)
				)
			)
		)
		(pad "2" smd rect
			(at 0 0.799846 270)
			(size 0.4572 0.508)
			(layers "F.Cu" "F.Mask" "F.Paste")
			(net "P1V05_SUS_NODE1_ADJ_S")
		)
		(zone
			(layer "F.Cu")
			(hatch none 0.5)
			(connect_pads
				(clearance 0)
			)
			(min_thickness 0.25)
			(keepout
				(tracks allowed)
				(vias not_allowed)
				(pads allowed)
				(copperpour not_allowed)
				(footprints allowed)
			)
			(placement
				(enabled no)
				(sheetname "")
			)
			(fill
				(thermal_gap 0.5)
				(thermal_bridge_width 0.5)
				(island_removal_mode 0)
			)
			(polygon
				(pts
					(xy 97.002346 -139.116054) (xy 96.392746 -139.116054) (xy 96.392746 -137.744454) (xy 97.002346 -137.744454)
				)
			)
		)
	)
	(footprint ""
		(layer "F.Cu")
		(at 169.728896 -41.679114)
		(property "Reference" "R266"
			(at -1.178814 -2.168398 0)
			(unlocked yes)
			(layer "F.SilkS")
			(effects
				(font
					(size 0.7874 0.5842)
					(thickness 0.1524)
				)
				(justify left)
			)
		)
		(property "Value" ""
			(at 0 0 0)
			(layer "F.Fab")
			(effects
				(font
					(size 1.27 1.27)
				)
			)
		)
		(duplicate_pad_numbers_are_jumpers no)
		(fp_line
			(start -0.7874 -0.4064)
			(end 0.7874 -0.4064)
			(stroke
				(width 0.1524)
				(type default)
			)
			(layer "F.SilkS")
		)
		(fp_line
			(start -0.7874 0.4064)
			(end -0.7874 -0.4064)
			(stroke
				(width 0.1524)
				(type default)
			)
			(layer "F.SilkS")
		)
		(fp_line
			(start 0.7874 -0.4064)
			(end 0.7874 0.4064)
			(stroke
				(width 0.1524)
				(type default)
			)
			(layer "F.SilkS")
		)
		(fp_line
			(start 0.7874 0.4064)
			(end -0.7874 0.4064)
			(stroke
				(width 0.1524)
				(type default)
			)
			(layer "F.SilkS")
		)
		(fp_poly
			(pts
				(xy -0.508 0.2794) (xy -0.508 0.2286) (xy -0.635 0.2286) (xy -0.635 -0.254) (xy -0.5334 -0.254)
				(xy -0.5334 -0.2794) (xy 0.5334 -0.2794) (xy 0.5334 -0.254) (xy 0.635 -0.254) (xy 0.635 0.254) (xy 0.5334 0.254)
				(xy 0.5334 0.2794)
			)
			(stroke
				(width 0)
				(type default)
			)
			(fill no)
			(layer "F.CrtYd")
		)
		(pad "1" smd rect
			(at 0.40005 0)
			(size 0.4572 0.508)
			(layers "F.Cu" "F.Mask" "F.Paste")
			(net "USB1_L_DP")
		)
		(pad "2" smd rect
			(at -0.40005 0)
			(size 0.4572 0.508)
			(layers "F.Cu" "F.Mask" "F.Paste")
			(net "USB1_DP")
		)
	)
)
